# T6G (Grand Teton) — schematic netlist excerpt (pin names and nets, part order shuffled) for the footprints in the layout excerpt that follows; sources: Cadence DE-HDL packaged netlist, KiCad conversion of 04192023_DAF0TMB3IC0_F0TG_MB_C_brd_V02_OCP.brd

R824  Q_RES  10K 5% CHIP  pkg 0402LF  page 164 : A = P3V3_AUX ; B = UART_CPU0_LVC3_UART0_TX
R4190  Q_RES  1K 1% EMPTY  pkg 0402LF  page 235 : A = P3V3_AUX ; B = U270_0_ADD2

(kicad_pcb
	(version 20260206)
	(generator "pcbnew")
	(generator_version "10.0")
	(general
		(thickness 1.6)
		(legacy_teardrops no)
	)
	(paper "A4")
	(title_block
		(title "04192023_DAF0TMB3IC0_F0TG_MB_C_brd_V02_OCP.brd")
		(comment 1 "Grand Teton / footprints 902-903 of 8354")
	)
	(layers
		(0 "F.Cu" signal "TOP")
		(4 "In1.Cu" signal "GND")
		(6 "In2.Cu" signal "IN1")
		(8 "In3.Cu" signal "GND1")
		(10 "In4.Cu" signal "IN2")
		(12 "In5.Cu" signal "GND2")
		(14 "In6.Cu" signal "IN3")
		(16 "In7.Cu" signal "GND3")
		(18 "In8.Cu" signal "VCC")
		(20 "In9.Cu" signal "VCC1")
		(22 "In10.Cu" signal "GND4")
		(24 "In11.Cu" signal "IN4")
		(26 "In12.Cu" signal "GND5")
		(28 "In13.Cu" signal "IN5")
		(30 "In14.Cu" signal "GND6")
		(32 "In15.Cu" signal "IN6")
		(34 "In16.Cu" signal "GND7")
		(2 "B.Cu" signal "BOTTOM")
		(9 "F.Adhes" user "F.Adhesive")
		(11 "B.Adhes" user "B.Adhesive")
		(13 "F.Paste" user "Package Geometry/Pastemask Top")
		(15 "B.Paste" user "Package Geometry/Pastemask Bottom")
		(5 "F.SilkS" user "Ref Des/Silkscreen Top")
		(7 "B.SilkS" user "Ref Des/Silkscreen Bottom")
		(1 "F.Mask" user "Board Geometry/Soldermask Top")
		(3 "B.Mask" user "Board Geometry/Soldermask Bottom")
		(17 "Dwgs.User" user "User.Drawings")
		(19 "Cmts.User" user "User.Comments")
		(21 "Eco1.User" user "User.Eco1")
		(23 "Eco2.User" user "User.Eco2")
		(25 "Edge.Cuts" user "Board Geometry/Outline")
		(27 "Margin" user)
		(31 "F.CrtYd" user "Package Geometry/Place Bound Top")
		(29 "B.CrtYd" user "Package Geometry/Place Bound Bottom")
		(35 "F.Fab" user "Ref Des/Assembly Top")
		(33 "B.Fab" user "Ref Des/Assembly Bottom")
	)
	(footprint ""
		(layer "F.Cu")
		(at 371.272308 -424.024552 -90)
		(property "Reference" "R4190"
			(at 0 0 270)
			(layer "F.SilkS")
			(hide yes)
			(effects
				(font
					(size 1.27 1.27)
				)
			)
		)
		(property "Value" ""
			(at 0 0 270)
			(layer "F.Fab")
			(effects
				(font
					(size 1.27 1.27)
				)
			)
		)
		(duplicate_pad_numbers_are_jumpers no)
		(fp_line
			(start -0.7874 0.4064)
			(end -0.7874 -0.4064)
			(stroke
				(width 0.1524)
				(type default)
			)
			(layer "F.SilkS")
		)
		(fp_line
			(start 0.7874 0.4064)
			(end -0.7874 0.4064)
			(stroke
				(width 0.1524)
				(type default)
			)
			(layer "F.SilkS")
		)
		(fp_line
			(start -0.7874 -0.4064)
			(end 0.7874 -0.4064)
			(stroke
				(width 0.1524)
				(type default)
			)
			(layer "F.SilkS")
		)
		(fp_line
			(start 0.7874 -0.4064)
			(end 0.7874 0.4064)
			(stroke
				(width 0.1524)
				(type default)
			)
			(layer "F.SilkS")
		)
		(fp_line
			(start -0.67945 0.3048)
			(end -0.67945 -0.305054)
			(stroke
				(width 0.1)
				(type default)
			)
			(layer "F.Fab")
		)
		(fp_line
			(start -0.12065 0.3048)
			(end -0.67945 0.3048)
			(stroke
				(width 0.1)
				(type default)
			)
			(layer "F.Fab")
		)
		(fp_line
			(start 0.120396 0.3048)
			(end 0.120396 0.2794)
			(stroke
				(width 0.1)
				(type default)
			)
			(layer "F.Fab")
		)
		(fp_line
			(start 0.67945 0.3048)
			(end 0.120396 0.3048)
			(stroke
				(width 0.1)
				(type default)
			)
			(layer "F.Fab")
		)
		(fp_line
			(start -0.12065 0.2794)
			(end -0.12065 0.3048)
			(stroke
				(width 0.1)
				(type default)
			)
			(layer "F.Fab")
		)
		(fp_line
			(start 0.120396 0.2794)
			(end -0.12065 0.2794)
			(stroke
				(width 0.1)
				(type default)
			)
			(layer "F.Fab")
		)
		(fp_line
			(start -0.12065 -0.2794)
			(end 0.12065 -0.2794)
			(stroke
				(width 0.1)
				(type default)
			)
			(layer "F.Fab")
		)
		(fp_line
			(start 0.12065 -0.2794)
			(end 0.12065 -0.3048)
			(stroke
				(width 0.1)
				(type default)
			)
			(layer "F.Fab")
		)
		(fp_line
			(start 0.12065 -0.3048)
			(end 0.67945 -0.3048)
			(stroke
				(width 0.1)
				(type default)
			)
			(layer "F.Fab")
		)
		(fp_line
			(start 0.67945 -0.3048)
			(end 0.67945 0.3048)
			(stroke
				(width 0.1)
				(type default)
			)
			(layer "F.Fab")
		)
		(fp_line
			(start -0.67945 -0.305054)
			(end -0.12065 -0.305054)
			(stroke
				(width 0.1)
				(type default)
			)
			(layer "F.Fab")
		)
		(fp_line
			(start -0.12065 -0.305054)
			(end -0.12065 -0.2794)
			(stroke
				(width 0.1)
				(type default)
			)
			(layer "F.Fab")
		)
		(pad "1" smd circle
			(at -0.40005 0 270)
			(size 0 0)
			(layers "F.Cu" "F.Mask" "F.Paste")
			(net "P3V3_AUX")
		)
		(pad "2" smd circle
			(at 0.40005 0 270)
			(size 0 0)
			(layers "F.Cu" "F.Mask" "F.Paste")
			(net "U270_0_ADD2")
		)
	)
	(footprint ""
		(layer "F.Cu")
		(at 366.534446 -28.306522 90)
		(property "Reference" "R824"
			(at 0 0 90)
			(layer "F.SilkS")
			(hide yes)
			(effects
				(font
					(size 1.27 1.27)
				)
			)
		)
		(property "Value" ""
			(at 0 0 90)
			(layer "F.Fab")
			(effects
				(font
					(size 1.27 1.27)
				)
			)
		)
		(duplicate_pad_numbers_are_jumpers no)
		(fp_line
			(start 0.7874 -0.4064)
			(end 0.7874 0.4064)
			(stroke
				(width 0.1524)
				(type default)
			)
			(layer "F.SilkS")
		)
		(fp_line
			(start -0.7874 -0.4064)
			(end 0.7874 -0.4064)
			(stroke
				(width 0.1524)
				(type default)
			)
			(layer "F.SilkS")
		)
		(fp_line
			(start 0.7874 0.4064)
			(end -0.7874 0.4064)
			(stroke
				(width 0.1524)
				(type default)
			)
			(layer "F.SilkS")
		)
		(fp_line
			(start -0.7874 0.4064)
			(end -0.7874 -0.4064)
			(stroke
				(width 0.1524)
				(type default)
			)
			(layer "F.SilkS")
		)
		(fp_line
			(start -0.12065 -0.305054)
			(end -0.12065 -0.2794)
			(stroke
				(width 0.1)
				(type default)
			)
			(layer "F.Fab")
		)
		(fp_line
			(start -0.67945 -0.305054)
			(end -0.12065 -0.305054)
			(stroke
				(width 0.1)
				(type default)
			)
			(layer "F.Fab")
		)
		(fp_line
			(start 0.67945 -0.3048)
			(end 0.67945 0.3048)
			(stroke
				(width 0.1)
				(type default)
			)
			(layer "F.Fab")
		)
		(fp_line
			(start 0.12065 -0.3048)
			(end 0.67945 -0.3048)
			(stroke
				(width 0.1)
				(type default)
			)
			(layer "F.Fab")
		)
		(fp_line
			(start 0.12065 -0.2794)
			(end 0.12065 -0.3048)
			(stroke
				(width 0.1)
				(type default)
			)
			(layer "F.Fab")
		)
		(fp_line
			(start -0.12065 -0.2794)
			(end 0.12065 -0.2794)
			(stroke
				(width 0.1)
				(type default)
			)
			(layer "F.Fab")
		)
		(fp_line
			(start 0.120396 0.2794)
			(end -0.12065 0.2794)
			(stroke
				(width 0.1)
				(type default)
			)
			(layer "F.Fab")
		)
		(fp_line
			(start -0.12065 0.2794)
			(end -0.12065 0.3048)
			(stroke
				(width 0.1)
				(type default)
			)
			(layer "F.Fab")
		)
		(fp_line
			(start 0.67945 0.3048)
			(end 0.120396 0.3048)
			(stroke
				(width 0.1)
				(type default)
			)
			(layer "F.Fab")
		)
		(fp_line
			(start 0.120396 0.3048)
			(end 0.120396 0.2794)
			(stroke
				(width 0.1)
				(type default)
			)
			(layer "F.Fab")
		)
		(fp_line
			(start -0.12065 0.3048)
			(end -0.67945 0.3048)
			(stroke
				(width 0.1)
				(type default)
			)
			(layer "F.Fab")
		)
		(fp_line
			(start -0.67945 0.3048)
			(end -0.67945 -0.305054)
			(stroke
				(width 0.1)
				(type default)
			)
			(layer "F.Fab")
		)
		(pad "1" smd circle
			(at -0.40005 0 90)
			(size 0 0)
			(layers "F.Cu" "F.Mask" "F.Paste")
			(net "P3V3_AUX")
		)
		(pad "2" smd circle
			(at 0.40005 0 90)
			(size 0 0)
			(layers "F.Cu" "F.Mask" "F.Paste")
			(net "UART_CPU0_LVC3_UART0_TX")
		)
	)
)
